(kicad_pcb
	(version 20260206)
	(generator "pcbnew")
	(generator_version "10.0")
	(general
		(thickness 1.6)
		(legacy_teardrops no)
	)
	(paper "A4")
	(title_block
		(title "baseboard — 13948-1b.1110WZS1818.brd")
		(comment 1 "Honey Badger (Wiwynn) / footprints 930-937 of 2523")
	)
	(layers
		(0 "F.Cu" signal "TOP")
		(4 "In1.Cu" signal "L2GND")
		(6 "In2.Cu" signal "L3")
		(8 "In3.Cu" signal "L4VCC")
		(10 "In4.Cu" signal "L5VCC")
		(12 "In5.Cu" signal "L6")
		(14 "In6.Cu" signal "L7GND")
		(2 "B.Cu" signal "BOTTOM")
		(9 "F.Adhes" user "F.Adhesive")
		(11 "B.Adhes" user "B.Adhesive")
		(13 "F.Paste" user "Package Geometry/Pastemask Top")
		(15 "B.Paste" user "Package Geometry/Pastemask Bottom")
		(5 "F.SilkS" user "Ref Des/Silkscreen Top")
		(7 "B.SilkS" user "Ref Des/Silkscreen Bottom")
		(1 "F.Mask" user "Board Geometry/Soldermask Top")
		(3 "B.Mask" user "Board Geometry/Soldermask Bottom")
		(17 "Dwgs.User" user "User.Drawings")
		(19 "Cmts.User" user "User.Comments")
		(21 "Eco1.User" user "User.Eco1")
		(23 "Eco2.User" user "User.Eco2")
		(25 "Edge.Cuts" user "Board Geometry/Outline")
		(27 "Margin" user)
		(31 "F.CrtYd" user "Package Geometry/Place Bound Top")
		(29 "B.CrtYd" user "Package Geometry/Place Bound Bottom")
		(35 "F.Fab" user "Ref Des/Assembly Top")
		(33 "B.Fab" user "Ref Des/Assembly Bottom")
	)
	(footprint ""
		(layer "F.Cu")
		(at 297.942 -98.679)
		(property "Reference" "C326"
			(at 0 0 0)
			(layer "F.SilkS")
			(hide yes)
			(effects
				(font
					(size 1.27 1.27)
				)
			)
		)
		(property "Value" "SCD1U16V2KX-3GP"
			(at 1.1811 -2.7051 0)
			(unlocked yes)
			(layer "F.Fab")
			(hide yes)
			(effects
				(font
					(size 1.016 1.016)
					(thickness 0.1524)
				)
			)
		)
		(property "Device Type" "C402H22"
			(at 1.1811 -4.2291 0)
			(unlocked yes)
			(layer "F.Fab")
			(hide yes)
			(effects
				(font
					(size 1.016 1.016)
					(thickness 0.1524)
				)
			)
		)
		(duplicate_pad_numbers_are_jumpers no)
		(fp_rect
			(start -0.4318 0.9525)
			(end 0.4318 -0.9525)
			(stroke
				(width 0)
				(type default)
			)
			(fill no)
			(layer "F.CrtYd")
		)
		(fp_rect
			(start -0.4318 0.9525)
			(end 0.4318 -0.9525)
			(stroke
				(width 0)
				(type default)
			)
			(fill no)
			(layer "F.Fab")
		)
		(pad "1" smd custom
			(at 0 -0.4445)
			(size 0.1524 0.1524)
			(layers "F.Cu" "F.Mask" "F.Paste")
			(net "P3V3_STBY")
			(options
				(clearance outline)
				(anchor circle)
			)
			(primitives
				(gr_poly
					(pts
						(arc
							(start 0.3048 -0.2032)
							(mid 0.275042 -0.275042)
							(end 0.2032 -0.3048)
						)
						(arc
							(start -0.2032 -0.3048)
							(mid -0.275042 -0.275042)
							(end -0.3048 -0.2032)
						)
						(arc
							(start -0.3048 0.2032)
							(mid -0.275042 0.275042)
							(end -0.2032 0.3048)
						)
						(arc
							(start 0.2032 0.3048)
							(mid 0.275042 0.275042)
							(end 0.3048 0.2032)
						)
					)
					(width 0)
					(fill yes)
				)
			)
		)
		(pad "2" smd custom
			(at 0 0.4445)
			(size 0.1524 0.1524)
			(layers "F.Cu" "F.Mask" "F.Paste")
			(net "GND")
			(options
				(clearance outline)
				(anchor circle)
			)
			(primitives
				(gr_poly
					(pts
						(arc
							(start 0.3048 -0.2032)
							(mid 0.275042 -0.275042)
							(end 0.2032 -0.3048)
						)
						(arc
							(start -0.2032 -0.3048)
							(mid -0.275042 -0.275042)
							(end -0.3048 -0.2032)
						)
						(arc
							(start -0.3048 0.2032)
							(mid -0.275042 0.275042)
							(end -0.2032 0.3048)
						)
						(arc
							(start 0.2032 0.3048)
							(mid 0.275042 0.275042)
							(end 0.3048 0.2032)
						)
					)
					(width 0)
					(fill yes)
				)
			)
		)
	)
	(footprint ""
		(layer "F.Cu")
		(at 48.768 -217.551 -90)
		(property "Reference" "R9023"
			(at 0 0 270)
			(layer "F.SilkS")
			(hide yes)
			(effects
				(font
					(size 1.27 1.27)
				)
			)
		)
		(property "Value" "57K6R2F-GP"
			(at 0.064008 -3.993896 270)
			(unlocked yes)
			(layer "F.Fab")
			(hide yes)
			(effects
				(font
					(size 1.016 1.016)
					(thickness 0.1524)
				)
			)
		)
		(property "Device Type" "R402H16"
			(at 0.064008 -5.517896 270)
			(unlocked yes)
			(layer "F.Fab")
			(hide yes)
			(effects
				(font
					(size 1.016 1.016)
					(thickness 0.1524)
				)
			)
		)
		(duplicate_pad_numbers_are_jumpers no)
		(fp_line
			(start -0.508 -0.9398)
			(end -0.508 0.9398)
			(stroke
				(width 0.1524)
				(type default)
			)
			(layer "F.SilkS")
		)
		(fp_line
			(start 0.508 -0.9398)
			(end -0.508 -0.9398)
			(stroke
				(width 0.1524)
				(type default)
			)
			(layer "F.SilkS")
		)
		(fp_rect
			(start -0.508 0.9398)
			(end 0.508 -0.9398)
			(stroke
				(width 0)
				(type default)
			)
			(fill no)
			(layer "F.CrtYd")
		)
		(fp_rect
			(start -0.508 0.9398)
			(end 0.508 -0.9398)
			(stroke
				(width 0)
				(type default)
			)
			(fill no)
			(layer "F.Fab")
		)
		(pad "1" smd custom
			(at 0 -0.4445 270)
			(size 0.1397 0.1397)
			(layers "F.Cu" "F.Mask" "F.Paste")
			(net "MB0_ISTART_R")
			(options
				(clearance outline)
				(anchor circle)
			)
			(primitives
				(gr_poly
					(pts
						(arc
							(start -0.1778 -0.2794)
							(mid -0.249642 -0.249642)
							(end -0.2794 -0.1778)
						)
						(arc
							(start -0.2794 0.1778)
							(mid -0.249642 0.249642)
							(end -0.1778 0.2794)
						)
						(arc
							(start 0.1778 0.2794)
							(mid 0.249642 0.249642)
							(end 0.2794 0.1778)
						)
						(arc
							(start 0.2794 -0.1778)
							(mid 0.249642 -0.249642)
							(end 0.1778 -0.2794)
						)
					)
					(width 0)
					(fill yes)
				)
			)
		)
		(pad "2" smd custom
			(at 0 0.4445 270)
			(size 0.1397 0.1397)
			(layers "F.Cu" "F.Mask" "F.Paste")
			(net "AGND_CURRENT_MON")
			(options
				(clearance outline)
				(anchor circle)
			)
			(primitives
				(gr_poly
					(pts
						(arc
							(start -0.1778 -0.2794)
							(mid -0.249642 -0.249642)
							(end -0.2794 -0.1778)
						)
						(arc
							(start -0.2794 0.1778)
							(mid -0.249642 0.249642)
							(end -0.1778 0.2794)
						)
						(arc
							(start 0.1778 0.2794)
							(mid 0.249642 0.249642)
							(end 0.2794 0.1778)
						)
						(arc
							(start 0.2794 -0.1778)
							(mid 0.249642 -0.249642)
							(end 0.1778 -0.2794)
						)
					)
					(width 0)
					(fill yes)
				)
			)
		)
	)
	(footprint ""
		(layer "F.Cu")
		(at 205.74 -121.158)
		(property "Reference" "PR9013"
			(at 0 0 0)
			(layer "F.SilkS")
			(hide yes)
			(effects
				(font
					(size 1.27 1.27)
				)
			)
		)
		(property "Value" "10R3F-GP"
			(at -0.0254 -2.5146 0)
			(unlocked yes)
			(layer "F.Fab")
			(hide yes)
			(effects
				(font
					(size 1.016 1.016)
					(thickness 0.1524)
				)
			)
		)
		(property "Device Type" "R603H22"
			(at -0.0254 -4.0386 0)
			(unlocked yes)
			(layer "F.Fab")
			(hide yes)
			(effects
				(font
					(size 1.016 1.016)
					(thickness 0.1524)
				)
			)
		)
		(duplicate_pad_numbers_are_jumpers no)
		(fp_line
			(start -0.4826 0)
			(end -0.2032 0)
			(stroke
				(width 0.2032)
				(type default)
			)
			(layer "F.SilkS")
		)
		(fp_line
			(start 0.2032 0)
			(end 0.4826 0)
			(stroke
				(width 0.2032)
				(type default)
			)
			(layer "F.SilkS")
		)
		(fp_rect
			(start -0.5842 1.3335)
			(end 0.5842 -1.3335)
			(stroke
				(width 0)
				(type default)
			)
			(fill no)
			(layer "F.CrtYd")
		)
		(fp_rect
			(start -0.5842 1.3335)
			(end 0.5842 -1.3335)
			(stroke
				(width 0)
				(type default)
			)
			(fill no)
			(layer "F.Fab")
		)
		(pad "1" smd custom
			(at 0 -0.762)
			(size 0.2159 0.2159)
			(layers "F.Cu" "F.Mask" "F.Paste")
			(net "P1V5_E_CC")
			(options
				(clearance outline)
				(anchor circle)
			)
			(primitives
				(gr_poly
					(pts
						(arc
							(start -0.3302 -0.4318)
							(mid -0.402042 -0.402042)
							(end -0.4318 -0.3302)
						)
						(arc
							(start -0.4318 0.3302)
							(mid -0.402042 0.402042)
							(end -0.3302 0.4318)
						)
						(arc
							(start 0.3302 0.4318)
							(mid 0.402042 0.402042)
							(end 0.4318 0.3302)
						)
						(arc
							(start 0.4318 -0.3302)
							(mid 0.402042 -0.402042)
							(end 0.3302 -0.4318)
						)
					)
					(width 0)
					(fill yes)
				)
			)
		)
		(pad "2" smd custom
			(at 0 0.762)
			(size 0.2159 0.2159)
			(layers "F.Cu" "F.Mask" "F.Paste")
			(net "P1V5_E_CC_R")
			(options
				(clearance outline)
				(anchor circle)
			)
			(primitives
				(gr_poly
					(pts
						(arc
							(start -0.3302 -0.4318)
							(mid -0.402042 -0.402042)
							(end -0.4318 -0.3302)
						)
						(arc
							(start -0.4318 0.3302)
							(mid -0.402042 0.402042)
							(end -0.3302 0.4318)
						)
						(arc
							(start 0.3302 0.4318)
							(mid 0.402042 0.402042)
							(end 0.4318 0.3302)
						)
						(arc
							(start 0.4318 -0.3302)
							(mid 0.402042 -0.402042)
							(end 0.3302 -0.4318)
						)
					)
					(width 0)
					(fill yes)
				)
			)
		)
	)
	(footprint ""
		(layer "F.Cu")
		(at 284.48 -159.893)
		(property "Reference" "TP115"
			(at 0 0 0)
			(layer "F.SilkS")
			(hide yes)
			(effects
				(font
					(size 1.27 1.27)
				)
			)
		)
		(property "Value" "TPAD28"
			(at 0.0127 -1.8034 0)
			(unlocked yes)
			(layer "F.Fab")
			(hide yes)
			(effects
				(font
					(size 1.016 1.016)
					(thickness 0.1524)
				)
			)
		)
		(property "Device Type" "TPAD28"
			(at 0.0127 -3.3274 0)
			(unlocked yes)
			(layer "F.Fab")
			(hide yes)
			(effects
				(font
					(size 1.016 1.016)
					(thickness 0.1524)
				)
			)
		)
		(duplicate_pad_numbers_are_jumpers no)
		(fp_poly
			(pts
				(arc
					(start 0.3556 0)
					(mid -0.3556 0)
					(end 0.3556 0)
				)
			)
			(stroke
				(width 0)
				(type default)
			)
			(fill no)
			(layer "F.CrtYd")
		)
		(fp_poly
			(pts
				(arc
					(start 0.6096 0)
					(mid -0.6096 0)
					(end 0.6096 0)
				)
			)
			(stroke
				(width 0)
				(type default)
			)
			(fill no)
			(layer "F.Fab")
		)
		(pad "1" smd circle
			(at 0 0)
			(size 0.7112 0.7112)
			(layers "F.Cu" "F.Mask" "F.Paste")
			(net "TP_BMC_GPIOF2")
		)
	)
	(footprint ""
		(layer "F.Cu")
		(at 274.193 -176.657 90)
		(property "Reference" "R357"
			(at 0 0 90)
			(layer "F.SilkS")
			(hide yes)
			(effects
				(font
					(size 1.27 1.27)
				)
			)
		)
		(property "Value" "3K3R2F-2-GP"
			(at 0.064008 -3.993896 90)
			(unlocked yes)
			(layer "F.Fab")
			(hide yes)
			(effects
				(font
					(size 1.016 1.016)
					(thickness 0.1524)
				)
			)
		)
		(property "Device Type" "R402H16"
			(at 0.064008 -5.517896 90)
			(unlocked yes)
			(layer "F.Fab")
			(hide yes)
			(effects
				(font
					(size 1.016 1.016)
					(thickness 0.1524)
				)
			)
		)
		(duplicate_pad_numbers_are_jumpers no)
		(fp_line
			(start 0.508 -0.9398)
			(end -0.508 -0.9398)
			(stroke
				(width 0.1524)
				(type default)
			)
			(layer "F.SilkS")
		)
		(fp_line
			(start -0.508 -0.9398)
			(end -0.508 0.9398)
			(stroke
				(width 0.1524)
				(type default)
			)
			(layer "F.SilkS")
		)
		(fp_rect
			(start -0.508 0.9398)
			(end 0.508 -0.9398)
			(stroke
				(width 0)
				(type default)
			)
			(fill no)
			(layer "F.CrtYd")
		)
		(fp_rect
			(start -0.508 0.9398)
			(end 0.508 -0.9398)
			(stroke
				(width 0)
				(type default)
			)
			(fill no)
			(layer "F.Fab")
		)
		(pad "1" smd custom
			(at 0 -0.4445 90)
			(size 0.1397 0.1397)
			(layers "F.Cu" "F.Mask" "F.Paste")
			(net "P3V3_STBY")
			(options
				(clearance outline)
				(anchor circle)
			)
			(primitives
				(gr_poly
					(pts
						(arc
							(start -0.1778 -0.2794)
							(mid -0.249642 -0.249642)
							(end -0.2794 -0.1778)
						)
						(arc
							(start -0.2794 0.1778)
							(mid -0.249642 0.249642)
							(end -0.1778 0.2794)
						)
						(arc
							(start 0.1778 0.2794)
							(mid 0.249642 0.249642)
							(end 0.2794 0.1778)
						)
						(arc
							(start 0.2794 -0.1778)
							(mid 0.249642 -0.249642)
							(end 0.1778 -0.2794)
						)
					)
					(width 0)
					(fill yes)
				)
			)
		)
		(pad "2" smd custom
			(at 0 0.4445 90)
			(size 0.1397 0.1397)
			(layers "F.Cu" "F.Mask" "F.Paste")
			(net "ROMA20")
			(options
				(clearance outline)
				(anchor circle)
			)
			(primitives
				(gr_poly
					(pts
						(arc
							(start -0.1778 -0.2794)
							(mid -0.249642 -0.249642)
							(end -0.2794 -0.1778)
						)
						(arc
							(start -0.2794 0.1778)
							(mid -0.249642 0.249642)
							(end -0.1778 0.2794)
						)
						(arc
							(start 0.1778 0.2794)
							(mid 0.249642 0.249642)
							(end 0.2794 0.1778)
						)
						(arc
							(start 0.2794 -0.1778)
							(mid 0.249642 -0.249642)
							(end 0.1778 -0.2794)
						)
					)
					(width 0)
					(fill yes)
				)
			)
		)
	)
	(footprint ""
		(layer "F.Cu")
		(at 86.49716 -41.275 -90)
		(property "Reference" "SC894"
			(at 0 0 270)
			(layer "F.SilkS")
			(hide yes)
			(effects
				(font
					(size 1.27 1.27)
				)
			)
		)
		(property "Value" "SCD01U10V1KX-GP"
			(at -2.8321 -1.7399 270)
			(unlocked yes)
			(layer "F.Fab")
			(hide yes)
			(effects
				(font
					(size 1.016 1.016)
					(thickness 0.1524)
				)
			)
		)
		(property "Device Type" "C0201H13"
			(at -2.8321 -3.2639 270)
			(unlocked yes)
			(layer "F.Fab")
			(hide yes)
			(effects
				(font
					(size 1.016 1.016)
					(thickness 0.1524)
				)
			)
		)
		(duplicate_pad_numbers_are_jumpers no)
		(fp_rect
			(start -0.2794 0.6477)
			(end 0.2794 -0.6477)
			(stroke
				(width 0)
				(type default)
			)
			(fill no)
			(layer "F.CrtYd")
		)
		(fp_rect
			(start -0.2794 0.6477)
			(end 0.2794 -0.6477)
			(stroke
				(width 0)
				(type default)
			)
			(fill no)
			(layer "F.Fab")
		)
		(pad "1" smd custom
			(at 0 -0.2794 270)
			(size 0.0762 0.0762)
			(layers "F.Cu" "F.Mask" "F.Paste")
			(net "SAS3008_RAID_TX_C_N6")
			(options
				(clearance outline)
				(anchor circle)
			)
			(primitives
				(gr_poly
					(pts
						(arc
							(start 0.1524 -0.127)
							(mid 0.137521 -0.162921)
							(end 0.1016 -0.1778)
						)
						(arc
							(start -0.1016 -0.1778)
							(mid -0.137521 -0.162921)
							(end -0.1524 -0.127)
						)
						(arc
							(start -0.1524 0.127)
							(mid -0.137521 0.162921)
							(end -0.1016 0.1778)
						)
						(arc
							(start 0.1016 0.1778)
							(mid 0.137521 0.162921)
							(end 0.1524 0.127)
						)
					)
					(width 0)
					(fill yes)
				)
			)
		)
		(pad "2" smd custom
			(at 0 0.2794 270)
			(size 0.0762 0.0762)
			(layers "F.Cu" "F.Mask" "F.Paste")
			(net "IOC_RAID_TX_N6")
			(options
				(clearance outline)
				(anchor circle)
			)
			(primitives
				(gr_poly
					(pts
						(arc
							(start 0.1524 -0.127)
							(mid 0.137521 -0.162921)
							(end 0.1016 -0.1778)
						)
						(arc
							(start -0.1016 -0.1778)
							(mid -0.137521 -0.162921)
							(end -0.1524 -0.127)
						)
						(arc
							(start -0.1524 0.127)
							(mid -0.137521 0.162921)
							(end -0.1016 0.1778)
						)
						(arc
							(start 0.1016 0.1778)
							(mid 0.137521 0.162921)
							(end 0.1524 0.127)
						)
					)
					(width 0)
					(fill yes)
				)
			)
		)
	)
	(footprint ""
		(layer "F.Cu")
		(at 84.328 -31.75 180)
		(property "Reference" "SC964"
			(at 0 0 180)
			(layer "F.SilkS")
			(hide yes)
			(effects
				(font
					(size 1.27 1.27)
				)
			)
		)
		(property "Value" "SCD1U6D3V1KX-GP"
			(at -2.8321 -1.7399 180)
			(unlocked yes)
			(layer "F.Fab")
			(hide yes)
			(effects
				(font
					(size 1.016 1.016)
					(thickness 0.1524)
				)
			)
		)
		(property "Device Type" "C0201H13"
			(at -2.8321 -3.2639 180)
			(unlocked yes)
			(layer "F.Fab")
			(hide yes)
			(effects
				(font
					(size 1.016 1.016)
					(thickness 0.1524)
				)
			)
		)
		(duplicate_pad_numbers_are_jumpers no)
		(fp_rect
			(start -0.2794 0.6477)
			(end 0.2794 -0.6477)
			(stroke
				(width 0)
				(type default)
			)
			(fill no)
			(layer "F.CrtYd")
		)
		(fp_rect
			(start -0.2794 0.6477)
			(end 0.2794 -0.6477)
			(stroke
				(width 0)
				(type default)
			)
			(fill no)
			(layer "F.Fab")
		)
		(pad "1" smd custom
			(at 0 -0.2794 180)
			(size 0.0762 0.0762)
			(layers "F.Cu" "F.Mask" "F.Paste")
			(net "SAS0_AVDD")
			(options
				(clearance outline)
				(anchor circle)
			)
			(primitives
				(gr_poly
					(pts
						(arc
							(start 0.1524 -0.127)
							(mid 0.137521 -0.162921)
							(end 0.1016 -0.1778)
						)
						(arc
							(start -0.1016 -0.1778)
							(mid -0.137521 -0.162921)
							(end -0.1524 -0.127)
						)
						(arc
							(start -0.1524 0.127)
							(mid -0.137521 0.162921)
							(end -0.1016 0.1778)
						)
						(arc
							(start 0.1016 0.1778)
							(mid 0.137521 0.162921)
							(end 0.1524 0.127)
						)
					)
					(width 0)
					(fill yes)
				)
			)
		)
		(pad "2" smd custom
			(at 0 0.2794 180)
			(size 0.0762 0.0762)
			(layers "F.Cu" "F.Mask" "F.Paste")
			(net "GND")
			(options
				(clearance outline)
				(anchor circle)
			)
			(primitives
				(gr_poly
					(pts
						(arc
							(start 0.1524 -0.127)
							(mid 0.137521 -0.162921)
							(end 0.1016 -0.1778)
						)
						(arc
							(start -0.1016 -0.1778)
							(mid -0.137521 -0.162921)
							(end -0.1524 -0.127)
						)
						(arc
							(start -0.1524 0.127)
							(mid -0.137521 0.162921)
							(end -0.1016 0.1778)
						)
						(arc
							(start 0.1016 0.1778)
							(mid 0.137521 0.162921)
							(end 0.1524 0.127)
						)
					)
					(width 0)
					(fill yes)
				)
			)
		)
	)
	(footprint ""
		(layer "F.Cu")
		(at 302.006 -188.976)
		(property "Reference" "R613"
			(at 0 0 0)
			(layer "F.SilkS")
			(hide yes)
			(effects
				(font
					(size 1.27 1.27)
				)
			)
		)
		(property "Value" "0R2J-2-GP"
			(at 0.064008 -3.993896 0)
			(unlocked yes)
			(layer "F.Fab")
			(hide yes)
			(effects
				(font
					(size 1.016 1.016)
					(thickness 0.1524)
				)
			)
		)
		(property "Device Type" "R402H16"
			(at 0.064008 -5.517896 0)
			(unlocked yes)
			(layer "F.Fab")
			(hide yes)
			(effects
				(font
					(size 1.016 1.016)
					(thickness 0.1524)
				)
			)
		)
		(duplicate_pad_numbers_are_jumpers no)
		(fp_line
			(start -0.508 -0.9398)
			(end -0.508 0.9398)
			(stroke
				(width 0.1524)
				(type default)
			)
			(layer "F.SilkS")
		)
		(fp_line
			(start 0.508 -0.9398)
			(end -0.508 -0.9398)
			(stroke
				(width 0.1524)
				(type default)
			)
			(layer "F.SilkS")
		)
		(fp_rect
			(start -0.508 0.9398)
			(end 0.508 -0.9398)
			(stroke
				(width 0)
				(type default)
			)
			(fill no)
			(layer "F.CrtYd")
		)
		(fp_rect
			(start -0.508 0.9398)
			(end 0.508 -0.9398)
			(stroke
				(width 0)
				(type default)
			)
			(fill no)
			(layer "F.Fab")
		)
		(pad "1" smd custom
			(at 0 -0.4445)
			(size 0.1397 0.1397)
			(layers "F.Cu" "F.Mask" "F.Paste")
			(net "BMC_UART_SWITCH_1")
			(options
				(clearance outline)
				(anchor circle)
			)
			(primitives
				(gr_poly
					(pts
						(arc
							(start -0.1778 -0.2794)
							(mid -0.249642 -0.249642)
							(end -0.2794 -0.1778)
						)
						(arc
							(start -0.2794 0.1778)
							(mid -0.249642 0.249642)
							(end -0.1778 0.2794)
						)
						(arc
							(start 0.1778 0.2794)
							(mid 0.249642 0.249642)
							(end 0.2794 0.1778)
						)
						(arc
							(start 0.2794 -0.1778)
							(mid 0.249642 -0.249642)
							(end 0.1778 -0.2794)
						)
					)
					(width 0)
					(fill yes)
				)
			)
		)
		(pad "2" smd custom
			(at 0 0.4445)
			(size 0.1397 0.1397)
			(layers "F.Cu" "F.Mask" "F.Paste")
			(net "BMC0_TACH11")
			(options
				(clearance outline)
				(anchor circle)
			)
			(primitives
				(gr_poly
					(pts
						(arc
							(start -0.1778 -0.2794)
							(mid -0.249642 -0.249642)
							(end -0.2794 -0.1778)
						)
						(arc
							(start -0.2794 0.1778)
							(mid -0.249642 0.249642)
							(end -0.1778 0.2794)
						)
						(arc
							(start 0.1778 0.2794)
							(mid 0.249642 0.249642)
							(end 0.2794 0.1778)
						)
						(arc
							(start 0.2794 -0.1778)
							(mid 0.249642 -0.249642)
							(end 0.1778 -0.2794)
						)
					)
					(width 0)
					(fill yes)
				)
			)
		)
	)
)
